(kicad_pcb
	(version 20241229)
	(generator "pcbnew")
	(generator_version "9.0")
	(general
		(thickness 1.6296)
		(legacy_teardrops no)
	)
	(paper "A3")
	(title_block
		(title "Thunderbolt to 10GbE adapter")
		(date "2026-04-21")
		(rev "1.1.0")
		(company "Antmicro Ltd")
		(comment 1 "www.antmicro.com")
		(comment 9 "footprints 667-671 of 703")
	)
	(layers
		(0 "F.Cu" signal)
		(4 "In1.Cu" signal)
		(6 "In2.Cu" signal)
		(8 "In3.Cu" signal)
		(10 "In4.Cu" signal)
		(12 "In5.Cu" signal)
		(14 "In6.Cu" signal)
		(2 "B.Cu" signal)
		(9 "F.Adhes" user "F.Adhesive")
		(11 "B.Adhes" user "B.Adhesive")
		(13 "F.Paste" user)
		(15 "B.Paste" user)
		(5 "F.SilkS" user "F.Silkscreen")
		(7 "B.SilkS" user "B.Silkscreen")
		(1 "F.Mask" user)
		(3 "B.Mask" user)
		(17 "Dwgs.User" user "User.Drawings")
		(19 "Cmts.User" user "User.Comments")
		(21 "Eco1.User" user "User.Eco1")
		(23 "Eco2.User" user "User.Eco2")
		(25 "Edge.Cuts" user)
		(27 "Margin" user)
		(31 "F.CrtYd" user "F.Courtyard")
		(29 "B.CrtYd" user "B.Courtyard")
		(35 "F.Fab" user)
		(33 "B.Fab" user)
	)
	(footprint "antmicro-footprints:C_0402_1005Metric"
		(layer "B.Cu")
		(at 133.85 133.099999 -90)
		(descr "Capacitor SMD 0402")
		(tags "capacitor SMD 0402")
		(property "Reference" "C15"
			(at -8.339997 -19.525001 90)
			(layer "B.SilkS")
			(effects
				(font
					(size 0.7 0.7)
					(thickness 0.15)
				)
				(justify mirror)
			)
		)
		(property "Value" "C_10u_0402"
			(at -1.022927 -2.155213 90)
			(layer "B.Fab")
			(effects
				(font
					(size 0.7 0.7)
					(thickness 0.15)
				)
				(justify left bottom mirror)
			)
		)
		(property "Datasheet" "https://www.yageo.com/en/Chart/Download/pdf/CC0402MRX5R5BB106"
			(at 0 0 90)
			(layer "B.Fab")
			(hide yes)
			(effects
				(font
					(size 1.27 1.27)
					(thickness 0.15)
				)
				(justify mirror)
			)
		)
		(property "Description" "SMD Multilayer Ceramic Capacitor, 10 µF, 6.3 V, 0402 [1005 Metric], ± 20%, X5R, CC Series"
			(at 0 0 90)
			(layer "B.Fab")
			(hide yes)
			(effects
				(font
					(size 1.27 1.27)
					(thickness 0.15)
				)
				(justify mirror)
			)
		)
		(property "MPN" "CC0402MRX5R5BB106"
			(at 0 0 270)
			(unlocked yes)
			(layer "B.Fab")
			(hide yes)
			(effects
				(font
					(size 1 1)
					(thickness 0.15)
				)
				(justify mirror)
			)
		)
		(property "Manufacturer" "YAGEO"
			(at 0 0 270)
			(unlocked yes)
			(layer "B.Fab")
			(hide yes)
			(effects
				(font
					(size 1 1)
					(thickness 0.15)
				)
				(justify mirror)
			)
		)
		(property "License" "Apache-2.0"
			(at 0 0 270)
			(unlocked yes)
			(layer "B.Fab")
			(hide yes)
			(effects
				(font
					(size 1 1)
					(thickness 0.15)
				)
				(justify mirror)
			)
		)
		(property "Val" "10u"
			(at 0 0 270)
			(unlocked yes)
			(layer "B.Fab")
			(hide yes)
			(effects
				(font
					(size 1 1)
					(thickness 0.15)
				)
				(justify mirror)
			)
		)
		(property "Voltage" ""
			(at 0 0 270)
			(unlocked yes)
			(layer "B.Fab")
			(hide yes)
			(effects
				(font
					(size 1 1)
					(thickness 0.15)
				)
				(justify mirror)
			)
		)
		(property "Dielectric" ""
			(at 0 0 270)
			(unlocked yes)
			(layer "B.Fab")
			(hide yes)
			(effects
				(font
					(size 1 1)
					(thickness 0.15)
				)
				(justify mirror)
			)
		)
		(property "Author" "Antmicro"
			(at 0 0 270)
			(unlocked yes)
			(layer "B.Fab")
			(hide yes)
			(effects
				(font
					(size 1 1)
					(thickness 0.15)
				)
				(justify mirror)
			)
		)
		(sheetname "/PD and TB DC-DC/")
		(sheetfile "PD_and_TB_DC_DC.kicad_sch")
		(attr smd)
		(fp_rect
			(start -0.925 0.47)
			(end 0.925 -0.47)
			(stroke
				(width 0.05)
				(type default)
			)
			(fill no)
			(layer "B.CrtYd")
		)
		(fp_line
			(start -0.494 0.25)
			(end 0.504 0.25)
			(stroke
				(width 0.15)
				(type solid)
			)
			(layer "B.Fab")
		)
		(fp_line
			(start 0.504 0.25)
			(end 0.504 -0.248)
			(stroke
				(width 0.15)
				(type solid)
			)
			(layer "B.Fab")
		)
		(fp_line
			(start -0.494 -0.248)
			(end -0.494 0.25)
			(stroke
				(width 0.15)
				(type solid)
			)
			(layer "B.Fab")
		)
		(fp_line
			(start 0.504 -0.248)
			(end -0.494 -0.248)
			(stroke
				(width 0.15)
				(type solid)
			)
			(layer "B.Fab")
		)
		(fp_text user "License: Apache-2.0"
			(at -0.939 -5.799 90)
			(layer "B.Fab")
			(effects
				(font
					(size 0.7 0.7)
					(thickness 0.15)
				)
				(justify left bottom mirror)
			)
		)
		(fp_text user "${REFERENCE}"
			(at -0.939 -4.599 90)
			(layer "B.Fab")
			(effects
				(font
					(size 0.7 0.7)
					(thickness 0.15)
				)
				(justify left bottom mirror)
			)
		)
		(fp_text user "Author: Antmicro"
			(at -0.939 -3.399 90)
			(layer "B.Fab")
			(effects
				(font
					(size 0.7 0.7)
					(thickness 0.15)
				)
				(justify left bottom mirror)
			)
		)
		(pad "1" smd roundrect
			(at -0.48 0 270)
			(size 0.59 0.64)
			(layers "B.Cu" "B.Mask" "B.Paste")
			(roundrect_rratio 0.25)
			(net 23 "GND")
			(pintype "passive")
		)
		(pad "2" smd roundrect
			(at 0.48 0 270)
			(size 0.59 0.64)
			(layers "B.Cu" "B.Mask" "B.Paste")
			(roundrect_rratio 0.25)
			(net 57 "+3V3_TB")
			(pintype "passive")
		)
	)
	(footprint "antmicro-footprints:R_0402_1005Metric"
		(layer "B.Cu")
		(at 134.840001 135.089997 -90)
		(descr "Resistor SMD 0402")
		(tags "resistor SMD 0402")
		(property "Reference" "R29"
			(at -8.339997 -19.525001 90)
			(layer "B.SilkS")
			(effects
				(font
					(size 0.7 0.7)
					(thickness 0.15)
				)
				(justify mirror)
			)
		)
		(property "Value" "R_15k_0.1%_0402"
			(at -1.011843 -1.772047 90)
			(layer "B.Fab")
			(effects
				(font
					(size 0.7 0.7)
					(thickness 0.15)
				)
				(justify left bottom mirror)
			)
		)
		(property "Datasheet" "https://www.mouser.com/datasheet/2/315/AOA0000C307-1149632.pdf"
			(at 0 0 90)
			(layer "B.Fab")
			(hide yes)
			(effects
				(font
					(size 1.27 1.27)
					(thickness 0.15)
				)
				(justify mirror)
			)
		)
		(property "Description" "SMD Chip Resistor, 15 kohm, ± 0.1%, 62.5 mW, 0402 [1005 Metric], Metal Film (Thin Film)"
			(at 0 0 90)
			(layer "B.Fab")
			(hide yes)
			(effects
				(font
					(size 1.27 1.27)
					(thickness 0.15)
				)
				(justify mirror)
			)
		)
		(property "MPN" "ERA-2ARB153X"
			(at 0 0 270)
			(unlocked yes)
			(layer "B.Fab")
			(hide yes)
			(effects
				(font
					(size 1 1)
					(thickness 0.15)
				)
				(justify mirror)
			)
		)
		(property "Manufacturer" "Panasonic"
			(at 0 0 270)
			(unlocked yes)
			(layer "B.Fab")
			(hide yes)
			(effects
				(font
					(size 1 1)
					(thickness 0.15)
				)
				(justify mirror)
			)
		)
		(property "License" "Apache-2.0"
			(at 0 0 270)
			(unlocked yes)
			(layer "B.Fab")
			(hide yes)
			(effects
				(font
					(size 1 1)
					(thickness 0.15)
				)
				(justify mirror)
			)
		)
		(property "Val" "15k"
			(at 0 0 270)
			(unlocked yes)
			(layer "B.Fab")
			(hide yes)
			(effects
				(font
					(size 1 1)
					(thickness 0.15)
				)
				(justify mirror)
			)
		)
		(property "Tolerance" "0.1%"
			(at 0 0 270)
			(unlocked yes)
			(layer "B.Fab")
			(hide yes)
			(effects
				(font
					(size 1 1)
					(thickness 0.15)
				)
				(justify mirror)
			)
		)
		(property "Author" "Antmicro"
			(at 0 0 270)
			(unlocked yes)
			(layer "B.Fab")
			(hide yes)
			(effects
				(font
					(size 1 1)
					(thickness 0.15)
				)
				(justify mirror)
			)
		)
		(sheetname "/PD and TB DC-DC/")
		(sheetfile "PD_and_TB_DC_DC.kicad_sch")
		(attr smd)
		(fp_rect
			(start -0.925 0.47)
			(end 0.925 -0.47)
			(stroke
				(width 0.05)
				(type default)
			)
			(fill no)
			(layer "B.CrtYd")
		)
		(fp_rect
			(start -0.5 0.25)
			(end 0.5 -0.25)
			(stroke
				(width 0.15)
				(type solid)
			)
			(fill no)
			(layer "B.Fab")
		)
		(fp_text user "Author: Antmicro"
			(at -0.95 -4.169 90)
			(layer "B.Fab")
			(effects
				(font
					(size 0.7 0.7)
					(thickness 0.15)
				)
				(justify left bottom mirror)
			)
		)
		(fp_text user "License: Apache-2.0"
			(at -0.95 -5.169 90)
			(layer "B.Fab")
			(effects
				(font
					(size 0.7 0.7)
					(thickness 0.15)
				)
				(justify left bottom mirror)
			)
		)
		(fp_text user "${REFERENCE}"
			(at -0.95 -3.168 90)
			(layer "B.Fab")
			(effects
				(font
					(size 0.7 0.7)
					(thickness 0.15)
				)
				(justify left bottom mirror)
			)
		)
		(pad "1" smd roundrect
			(at -0.48 0 270)
			(size 0.59 0.64)
			(layers "B.Cu" "B.Mask" "B.Paste")
			(roundrect_rratio 0.25)
			(net 212 "Net-(U3-R_OSC)")
			(pintype "passive")
		)
		(pad "2" smd roundrect
			(at 0.48 0 270)
			(size 0.59 0.64)
			(layers "B.Cu" "B.Mask" "B.Paste")
			(roundrect_rratio 0.25)
			(net 23 "GND")
			(pintype "passive")
		)
	)
	(footprint "antmicro-footprints:R_0402_1005Metric"
		(layer "B.Cu")
		(at 139.199998 132.600001 180)
		(descr "Resistor SMD 0402")
		(tags "resistor SMD 0402")
		(property "Reference" "R9"
			(at -19.525001 8.1 0)
			(layer "B.SilkS")
			(effects
				(font
					(size 0.7 0.7)
					(thickness 0.15)
				)
				(justify mirror)
			)
		)
		(property "Value" "R_2k2_0402"
			(at -1.011843 -1.772047 0)
			(layer "B.Fab")
			(effects
				(font
					(size 0.7 0.7)
					(thickness 0.15)
				)
				(justify left bottom mirror)
			)
		)
		(property "Datasheet" "https://www.bourns.com/docs/product-datasheets/cr.pdf"
			(at 0 0 0)
			(layer "B.Fab")
			(hide yes)
			(effects
				(font
					(size 1.27 1.27)
					(thickness 0.15)
				)
				(justify mirror)
			)
		)
		(property "Description" "SMD Chip Resistor, 2.2 kohm, ± 1%, 62.5 mW, 0402 [1005 Metric], Thick Film, General Purpose"
			(at 0 0 0)
			(layer "B.Fab")
			(hide yes)
			(effects
				(font
					(size 1.27 1.27)
					(thickness 0.15)
				)
				(justify mirror)
			)
		)
		(property "MPN" "CR0402-FX-2201GLF"
			(at 0 0 180)
			(unlocked yes)
			(layer "B.Fab")
			(hide yes)
			(effects
				(font
					(size 1 1)
					(thickness 0.15)
				)
				(justify mirror)
			)
		)
		(property "Manufacturer" "Bourns"
			(at 0 0 180)
			(unlocked yes)
			(layer "B.Fab")
			(hide yes)
			(effects
				(font
					(size 1 1)
					(thickness 0.15)
				)
				(justify mirror)
			)
		)
		(property "License" "Apache-2.0"
			(at 0 0 180)
			(unlocked yes)
			(layer "B.Fab")
			(hide yes)
			(effects
				(font
					(size 1 1)
					(thickness 0.15)
				)
				(justify mirror)
			)
		)
		(property "Val" "2k2"
			(at 0 0 180)
			(unlocked yes)
			(layer "B.Fab")
			(hide yes)
			(effects
				(font
					(size 1 1)
					(thickness 0.15)
				)
				(justify mirror)
			)
		)
		(property "Tolerance" "1%"
			(at 0 0 180)
			(unlocked yes)
			(layer "B.Fab")
			(hide yes)
			(effects
				(font
					(size 1 1)
					(thickness 0.15)
				)
				(justify mirror)
			)
		)
		(property "Author" "Antmicro"
			(at 0 0 180)
			(unlocked yes)
			(layer "B.Fab")
			(hide yes)
			(effects
				(font
					(size 1 1)
					(thickness 0.15)
				)
				(justify mirror)
			)
		)
		(sheetname "/PD and TB DC-DC/")
		(sheetfile "PD_and_TB_DC_DC.kicad_sch")
		(attr smd)
		(fp_rect
			(start -0.925 0.47)
			(end 0.925 -0.47)
			(stroke
				(width 0.05)
				(type default)
			)
			(fill no)
			(layer "B.CrtYd")
		)
		(fp_rect
			(start -0.5 0.25)
			(end 0.5 -0.25)
			(stroke
				(width 0.15)
				(type solid)
			)
			(fill no)
			(layer "B.Fab")
		)
		(fp_text user "Author: Antmicro"
			(at -0.95 -4.169 0)
			(layer "B.Fab")
			(effects
				(font
					(size 0.7 0.7)
					(thickness 0.15)
				)
				(justify left bottom mirror)
			)
		)
		(fp_text user "License: Apache-2.0"
			(at -0.95 -5.169 0)
			(layer "B.Fab")
			(effects
				(font
					(size 0.7 0.7)
					(thickness 0.15)
				)
				(justify left bottom mirror)
			)
		)
		(fp_text user "${REFERENCE}"
			(at -0.95 -3.168 0)
			(layer "B.Fab")
			(effects
				(font
					(size 0.7 0.7)
					(thickness 0.15)
				)
				(justify left bottom mirror)
			)
		)
		(pad "1" smd roundrect
			(at -0.48 0 180)
			(size 0.59 0.64)
			(layers "B.Cu" "B.Mask" "B.Paste")
			(roundrect_rratio 0.25)
			(net 373 "/PD and TB DC-DC/I2C1.SCL")
			(pintype "passive")
		)
		(pad "2" smd roundrect
			(at 0.48 0 180)
			(size 0.59 0.64)
			(layers "B.Cu" "B.Mask" "B.Paste")
			(roundrect_rratio 0.25)
			(net 57 "+3V3_TB")
			(pintype "passive")
		)
	)
	(footprint "antmicro-footprints:C_0402_1005Metric"
		(layer "B.Cu")
		(at 157.961866 86.015117)
		(descr "Capacitor SMD 0402")
		(tags "capacitor SMD 0402")
		(property "Reference" "C192"
			(at 20.793134 9.464883 180)
			(layer "B.SilkS")
			(effects
				(font
					(size 0.7 0.7)
					(thickness 0.15)
				)
				(justify mirror)
			)
		)
		(property "Value" "C_1u_25V_0402"
			(at -1.022927 -2.155213 180)
			(layer "B.Fab")
			(effects
				(font
					(size 0.7 0.7)
					(thickness 0.15)
				)
				(justify left bottom mirror)
			)
		)
		(property "Datasheet" "https://www.murata.com/products/productdetail?partno=GRM155R61E105KE11%23"
			(at 0 0 180)
			(layer "B.Fab")
			(hide yes)
			(effects
				(font
					(size 1.27 1.27)
					(thickness 0.15)
				)
				(justify mirror)
			)
		)
		(property "Description" "SMD Multilayer Ceramic Capacitor, 1 µF, 25 V, 0402 [1005 Metric], ± 10%, X5R, GRM Series"
			(at 0 0 180)
			(layer "B.Fab")
			(hide yes)
			(effects
				(font
					(size 1.27 1.27)
					(thickness 0.15)
				)
				(justify mirror)
			)
		)
		(property "MPN" "GRM155R61E105KE11J"
			(at 0 0 0)
			(unlocked yes)
			(layer "B.Fab")
			(hide yes)
			(effects
				(font
					(size 1 1)
					(thickness 0.15)
				)
				(justify mirror)
			)
		)
		(property "Manufacturer" "Murata"
			(at 0 0 0)
			(unlocked yes)
			(layer "B.Fab")
			(hide yes)
			(effects
				(font
					(size 1 1)
					(thickness 0.15)
				)
				(justify mirror)
			)
		)
		(property "License" "Apache-2.0"
			(at 0 0 0)
			(unlocked yes)
			(layer "B.Fab")
			(hide yes)
			(effects
				(font
					(size 1 1)
					(thickness 0.15)
				)
				(justify mirror)
			)
		)
		(property "Author" "Antmicro"
			(at 0 0 0)
			(unlocked yes)
			(layer "B.Fab")
			(hide yes)
			(effects
				(font
					(size 1 1)
					(thickness 0.15)
				)
				(justify mirror)
			)
		)
		(property "Val" "1u"
			(at 0 0 0)
			(unlocked yes)
			(layer "B.Fab")
			(hide yes)
			(effects
				(font
					(size 1 1)
					(thickness 0.15)
				)
				(justify mirror)
			)
		)
		(property "Voltage" "25V"
			(at 0 0 0)
			(unlocked yes)
			(layer "B.Fab")
			(hide yes)
			(effects
				(font
					(size 1 1)
					(thickness 0.15)
				)
				(justify mirror)
			)
		)
		(property "Dielectric" "X5R"
			(at 0 0 0)
			(unlocked yes)
			(layer "B.Fab")
			(hide yes)
			(effects
				(font
					(size 1 1)
					(thickness 0.15)
				)
				(justify mirror)
			)
		)
		(sheetname "/X710-AT2 power/")
		(sheetfile "x710-at2-power.kicad_sch")
		(attr smd)
		(fp_rect
			(start -0.925 0.47)
			(end 0.925 -0.47)
			(stroke
				(width 0.05)
				(type default)
			)
			(fill no)
			(layer "B.CrtYd")
		)
		(fp_line
			(start -0.494 -0.248)
			(end -0.494 0.25)
			(stroke
				(width 0.15)
				(type solid)
			)
			(layer "B.Fab")
		)
		(fp_line
			(start -0.494 0.25)
			(end 0.504 0.25)
			(stroke
				(width 0.15)
				(type solid)
			)
			(layer "B.Fab")
		)
		(fp_line
			(start 0.504 -0.248)
			(end -0.494 -0.248)
			(stroke
				(width 0.15)
				(type solid)
			)
			(layer "B.Fab")
		)
		(fp_line
			(start 0.504 0.25)
			(end 0.504 -0.248)
			(stroke
				(width 0.15)
				(type solid)
			)
			(layer "B.Fab")
		)
		(fp_text user "Author: Antmicro"
			(at -0.939 -3.399 180)
			(layer "B.Fab")
			(effects
				(font
					(size 0.7 0.7)
					(thickness 0.15)
				)
				(justify left bottom mirror)
			)
		)
		(fp_text user "License: Apache-2.0"
			(at -0.939 -5.799 180)
			(layer "B.Fab")
			(effects
				(font
					(size 0.7 0.7)
					(thickness 0.15)
				)
				(justify left bottom mirror)
			)
		)
		(fp_text user "${REFERENCE}"
			(at -0.939 -4.599 180)
			(layer "B.Fab")
			(effects
				(font
					(size 0.7 0.7)
					(thickness 0.15)
				)
				(justify left bottom mirror)
			)
		)
		(pad "1" smd roundrect
			(at -0.48 0)
			(size 0.59 0.64)
			(layers "B.Cu" "B.Mask" "B.Paste")
			(roundrect_rratio 0.25)
			(net 23 "GND")
			(pintype "passive")
		)
		(pad "2" smd roundrect
			(at 0.48 0)
			(size 0.59 0.64)
			(layers "B.Cu" "B.Mask" "B.Paste")
			(roundrect_rratio 0.25)
			(net 10 "AVDDH")
			(pintype "passive")
		)
	)
	(footprint "antmicro-footprints:C_0402_1005Metric"
		(layer "B.Cu")
		(at 138.35 139.55 180)
		(descr "Capacitor SMD 0402")
		(tags "capacitor SMD 0402")
		(property "Reference" "C13"
			(at -19.525001 8.1 0)
			(layer "B.SilkS")
			(effects
				(font
					(size 0.7 0.7)
					(thickness 0.15)
				)
				(justify mirror)
			)
		)
		(property "Value" "C_4u7_25V_0402"
			(at -1.022927 -2.155213 0)
			(layer "B.Fab")
			(effects
				(font
					(size 0.7 0.7)
					(thickness 0.15)
				)
				(justify left bottom mirror)
			)
		)
		(property "Datasheet" "https://www.murata.com/products/productdetail?partno=GRM155C61E475ME15%23"
			(at 0 0 0)
			(layer "B.Fab")
			(hide yes)
			(effects
				(font
					(size 1.27 1.27)
					(thickness 0.15)
				)
				(justify mirror)
			)
		)
		(property "Description" "SMD Multilayer Ceramic Capacitor"
			(at 0 0 0)
			(layer "B.Fab")
			(hide yes)
			(effects
				(font
					(size 1.27 1.27)
					(thickness 0.15)
				)
				(justify mirror)
			)
		)
		(property "MPN" "GRM155C61E475ME15J"
			(at 0 0 180)
			(unlocked yes)
			(layer "B.Fab")
			(hide yes)
			(effects
				(font
					(size 1 1)
					(thickness 0.15)
				)
				(justify mirror)
			)
		)
		(property "Manufacturer" "Murata"
			(at 0 0 180)
			(unlocked yes)
			(layer "B.Fab")
			(hide yes)
			(effects
				(font
					(size 1 1)
					(thickness 0.15)
				)
				(justify mirror)
			)
		)
		(property "License" "Apache-2.0"
			(at 0 0 180)
			(unlocked yes)
			(layer "B.Fab")
			(hide yes)
			(effects
				(font
					(size 1 1)
					(thickness 0.15)
				)
				(justify mirror)
			)
		)
		(property "Val" "4u7"
			(at 0 0 180)
			(unlocked yes)
			(layer "B.Fab")
			(hide yes)
			(effects
				(font
					(size 1 1)
					(thickness 0.15)
				)
				(justify mirror)
			)
		)
		(property "Voltage" "25V"
			(at 0 0 180)
			(unlocked yes)
			(layer "B.Fab")
			(hide yes)
			(effects
				(font
					(size 1 1)
					(thickness 0.15)
				)
				(justify mirror)
			)
		)
		(property "Dielectric" "X5S"
			(at 0 0 180)
			(unlocked yes)
			(layer "B.Fab")
			(hide yes)
			(effects
				(font
					(size 1 1)
					(thickness 0.15)
				)
				(justify mirror)
			)
		)
		(property "Author" "Antmicro"
			(at 0 0 180)
			(unlocked yes)
			(layer "B.Fab")
			(hide yes)
			(effects
				(font
					(size 1 1)
					(thickness 0.15)
				)
				(justify mirror)
			)
		)
		(sheetname "/PD and TB DC-DC/")
		(sheetfile "PD_and_TB_DC_DC.kicad_sch")
		(attr smd)
		(fp_rect
			(start -0.925 0.47)
			(end 0.925 -0.47)
			(stroke
				(width 0.05)
				(type default)
			)
			(fill no)
			(layer "B.CrtYd")
		)
		(fp_line
			(start 0.504 0.25)
			(end 0.504 -0.248)
			(stroke
				(width 0.15)
				(type solid)
			)
			(layer "B.Fab")
		)
		(fp_line
			(start 0.504 -0.248)
			(end -0.494 -0.248)
			(stroke
				(width 0.15)
				(type solid)
			)
			(layer "B.Fab")
		)
		(fp_line
			(start -0.494 0.25)
			(end 0.504 0.25)
			(stroke
				(width 0.15)
				(type solid)
			)
			(layer "B.Fab")
		)
		(fp_line
			(start -0.494 -0.248)
			(end -0.494 0.25)
			(stroke
				(width 0.15)
				(type solid)
			)
			(layer "B.Fab")
		)
		(fp_text user "${REFERENCE}"
			(at -0.939 -4.599 0)
			(layer "B.Fab")
			(effects
				(font
					(size 0.7 0.7)
					(thickness 0.15)
				)
				(justify left bottom mirror)
			)
		)
		(fp_text user "Author: Antmicro"
			(at -0.939 -3.399 0)
			(layer "B.Fab")
			(effects
				(font
					(size 0.7 0.7)
					(thickness 0.15)
				)
				(justify left bottom mirror)
			)
		)
		(fp_text user "License: Apache-2.0"
			(at -0.939 -5.799 0)
			(layer "B.Fab")
			(effects
				(font
					(size 0.7 0.7)
					(thickness 0.15)
				)
				(justify left bottom mirror)
			)
		)
		(pad "1" smd roundrect
			(at -0.48 0 180)
			(size 0.59 0.64)
			(layers "B.Cu" "B.Mask" "B.Paste")
			(roundrect_rratio 0.25)
			(net 23 "GND")
			(pintype "passive")
		)
		(pad "2" smd roundrect
			(at 0.48 0 180)
			(size 0.59 0.64)
			(layers "B.Cu" "B.Mask" "B.Paste")
			(roundrect_rratio 0.25)
			(net 173 "PP_5V0")
			(pintype "passive")
		)
	)
)
